(kicad_pcb
	(version 20260206)
	(generator "pcbnew")
	(generator_version "10.0")
	(general
		(thickness 1.6)
		(legacy_teardrops no)
	)
	(paper "A4")
	(title_block
		(title "baseboard — 13948-1b.1110WZS1818.brd")
		(comment 1 "Honey Badger (Wiwynn) / footprints 836-843 of 2523")
	)
	(layers
		(0 "F.Cu" signal "TOP")
		(4 "In1.Cu" signal "L2GND")
		(6 "In2.Cu" signal "L3")
		(8 "In3.Cu" signal "L4VCC")
		(10 "In4.Cu" signal "L5VCC")
		(12 "In5.Cu" signal "L6")
		(14 "In6.Cu" signal "L7GND")
		(2 "B.Cu" signal "BOTTOM")
		(9 "F.Adhes" user "F.Adhesive")
		(11 "B.Adhes" user "B.Adhesive")
		(13 "F.Paste" user "Package Geometry/Pastemask Top")
		(15 "B.Paste" user "Package Geometry/Pastemask Bottom")
		(5 "F.SilkS" user "Ref Des/Silkscreen Top")
		(7 "B.SilkS" user "Ref Des/Silkscreen Bottom")
		(1 "F.Mask" user "Board Geometry/Soldermask Top")
		(3 "B.Mask" user "Board Geometry/Soldermask Bottom")
		(17 "Dwgs.User" user "User.Drawings")
		(19 "Cmts.User" user "User.Comments")
		(21 "Eco1.User" user "User.Eco1")
		(23 "Eco2.User" user "User.Eco2")
		(25 "Edge.Cuts" user "Board Geometry/Outline")
		(27 "Margin" user)
		(31 "F.CrtYd" user "Package Geometry/Place Bound Top")
		(29 "B.CrtYd" user "Package Geometry/Place Bound Bottom")
		(35 "F.Fab" user "Ref Des/Assembly Top")
		(33 "B.Fab" user "Ref Des/Assembly Bottom")
	)
	(footprint ""
		(layer "F.Cu")
		(at 317.627 -176.276)
		(property "Reference" "C191"
			(at 0 0 0)
			(layer "F.SilkS")
			(hide yes)
			(effects
				(font
					(size 1.27 1.27)
				)
			)
		)
		(property "Value" "SCD1U16V2KX-3GP"
			(at 1.1811 -2.7051 0)
			(unlocked yes)
			(layer "F.Fab")
			(hide yes)
			(effects
				(font
					(size 1.016 1.016)
					(thickness 0.1524)
				)
			)
		)
		(property "Device Type" "C402H22"
			(at 1.1811 -4.2291 0)
			(unlocked yes)
			(layer "F.Fab")
			(hide yes)
			(effects
				(font
					(size 1.016 1.016)
					(thickness 0.1524)
				)
			)
		)
		(duplicate_pad_numbers_are_jumpers no)
		(fp_rect
			(start -0.4318 0.9525)
			(end 0.4318 -0.9525)
			(stroke
				(width 0)
				(type default)
			)
			(fill no)
			(layer "F.CrtYd")
		)
		(fp_rect
			(start -0.4318 0.9525)
			(end 0.4318 -0.9525)
			(stroke
				(width 0)
				(type default)
			)
			(fill no)
			(layer "F.Fab")
		)
		(pad "1" smd custom
			(at 0 -0.4445)
			(size 0.1524 0.1524)
			(layers "F.Cu" "F.Mask" "F.Paste")
			(net "ADCVREFFN")
			(options
				(clearance outline)
				(anchor circle)
			)
			(primitives
				(gr_poly
					(pts
						(arc
							(start 0.3048 -0.2032)
							(mid 0.275042 -0.275042)
							(end 0.2032 -0.3048)
						)
						(arc
							(start -0.2032 -0.3048)
							(mid -0.275042 -0.275042)
							(end -0.3048 -0.2032)
						)
						(arc
							(start -0.3048 0.2032)
							(mid -0.275042 0.275042)
							(end -0.2032 0.3048)
						)
						(arc
							(start 0.2032 0.3048)
							(mid 0.275042 0.275042)
							(end 0.3048 0.2032)
						)
					)
					(width 0)
					(fill yes)
				)
			)
		)
		(pad "2" smd custom
			(at 0 0.4445)
			(size 0.1524 0.1524)
			(layers "F.Cu" "F.Mask" "F.Paste")
			(net "ADCVREFFP")
			(options
				(clearance outline)
				(anchor circle)
			)
			(primitives
				(gr_poly
					(pts
						(arc
							(start 0.3048 -0.2032)
							(mid 0.275042 -0.275042)
							(end 0.2032 -0.3048)
						)
						(arc
							(start -0.2032 -0.3048)
							(mid -0.275042 -0.275042)
							(end -0.3048 -0.2032)
						)
						(arc
							(start -0.3048 0.2032)
							(mid -0.275042 0.275042)
							(end -0.2032 0.3048)
						)
						(arc
							(start 0.2032 0.3048)
							(mid 0.275042 0.275042)
							(end 0.3048 0.2032)
						)
					)
					(width 0)
					(fill yes)
				)
			)
		)
	)
	(footprint ""
		(layer "F.Cu")
		(at 302.387 -222.377 -90)
		(property "Reference" "R638"
			(at 0 0 270)
			(layer "F.SilkS")
			(hide yes)
			(effects
				(font
					(size 1.27 1.27)
				)
			)
		)
		(property "Value" "4K7R2F-GP"
			(at 0.064008 -3.993896 270)
			(unlocked yes)
			(layer "F.Fab")
			(hide yes)
			(effects
				(font
					(size 1.016 1.016)
					(thickness 0.1524)
				)
			)
		)
		(property "Device Type" "R402H16"
			(at 0.064008 -5.517896 270)
			(unlocked yes)
			(layer "F.Fab")
			(hide yes)
			(effects
				(font
					(size 1.016 1.016)
					(thickness 0.1524)
				)
			)
		)
		(duplicate_pad_numbers_are_jumpers no)
		(fp_line
			(start -0.508 -0.9398)
			(end -0.508 0.9398)
			(stroke
				(width 0.1524)
				(type default)
			)
			(layer "F.SilkS")
		)
		(fp_line
			(start 0.508 -0.9398)
			(end -0.508 -0.9398)
			(stroke
				(width 0.1524)
				(type default)
			)
			(layer "F.SilkS")
		)
		(fp_rect
			(start -0.508 0.9398)
			(end 0.508 -0.9398)
			(stroke
				(width 0)
				(type default)
			)
			(fill no)
			(layer "F.CrtYd")
		)
		(fp_rect
			(start -0.508 0.9398)
			(end 0.508 -0.9398)
			(stroke
				(width 0)
				(type default)
			)
			(fill no)
			(layer "F.Fab")
		)
		(pad "1" smd custom
			(at 0 -0.4445 270)
			(size 0.1397 0.1397)
			(layers "F.Cu" "F.Mask" "F.Paste")
			(net "P3V3_STBY")
			(options
				(clearance outline)
				(anchor circle)
			)
			(primitives
				(gr_poly
					(pts
						(arc
							(start -0.1778 -0.2794)
							(mid -0.249642 -0.249642)
							(end -0.2794 -0.1778)
						)
						(arc
							(start -0.2794 0.1778)
							(mid -0.249642 0.249642)
							(end -0.1778 0.2794)
						)
						(arc
							(start 0.1778 0.2794)
							(mid 0.249642 0.249642)
							(end 0.2794 0.1778)
						)
						(arc
							(start 0.2794 -0.1778)
							(mid 0.249642 -0.249642)
							(end 0.1778 -0.2794)
						)
					)
					(width 0)
					(fill yes)
				)
			)
		)
		(pad "2" smd custom
			(at 0 0.4445 270)
			(size 0.1397 0.1397)
			(layers "F.Cu" "F.Mask" "F.Paste")
			(net "DEBUG_OE_1_N")
			(options
				(clearance outline)
				(anchor circle)
			)
			(primitives
				(gr_poly
					(pts
						(arc
							(start -0.1778 -0.2794)
							(mid -0.249642 -0.249642)
							(end -0.2794 -0.1778)
						)
						(arc
							(start -0.2794 0.1778)
							(mid -0.249642 0.249642)
							(end -0.1778 0.2794)
						)
						(arc
							(start 0.1778 0.2794)
							(mid 0.249642 0.249642)
							(end 0.2794 0.1778)
						)
						(arc
							(start 0.2794 -0.1778)
							(mid 0.249642 -0.249642)
							(end 0.1778 -0.2794)
						)
					)
					(width 0)
					(fill yes)
				)
			)
		)
	)
	(footprint ""
		(layer "F.Cu")
		(at 316.611 -115.824 90)
		(property "Reference" "PR32"
			(at 0 0 90)
			(layer "F.SilkS")
			(hide yes)
			(effects
				(font
					(size 1.27 1.27)
				)
			)
		)
		(property "Value" "866KR2F-GP"
			(at 0.064008 -3.993896 90)
			(unlocked yes)
			(layer "F.Fab")
			(hide yes)
			(effects
				(font
					(size 1.016 1.016)
					(thickness 0.1524)
				)
			)
		)
		(property "Device Type" "R402H16"
			(at 0.064008 -5.517896 90)
			(unlocked yes)
			(layer "F.Fab")
			(hide yes)
			(effects
				(font
					(size 1.016 1.016)
					(thickness 0.1524)
				)
			)
		)
		(duplicate_pad_numbers_are_jumpers no)
		(fp_line
			(start 0.508 -0.9398)
			(end -0.508 -0.9398)
			(stroke
				(width 0.1524)
				(type default)
			)
			(layer "F.SilkS")
		)
		(fp_line
			(start -0.508 -0.9398)
			(end -0.508 0.9398)
			(stroke
				(width 0.1524)
				(type default)
			)
			(layer "F.SilkS")
		)
		(fp_rect
			(start -0.508 0.9398)
			(end 0.508 -0.9398)
			(stroke
				(width 0)
				(type default)
			)
			(fill no)
			(layer "F.CrtYd")
		)
		(fp_rect
			(start -0.508 0.9398)
			(end 0.508 -0.9398)
			(stroke
				(width 0)
				(type default)
			)
			(fill no)
			(layer "F.Fab")
		)
		(pad "1" smd custom
			(at 0 -0.4445 90)
			(size 0.1397 0.1397)
			(layers "F.Cu" "F.Mask" "F.Paste")
			(net "P3V3_STBY_VREG")
			(options
				(clearance outline)
				(anchor circle)
			)
			(primitives
				(gr_poly
					(pts
						(arc
							(start -0.1778 -0.2794)
							(mid -0.249642 -0.249642)
							(end -0.2794 -0.1778)
						)
						(arc
							(start -0.2794 0.1778)
							(mid -0.249642 0.249642)
							(end -0.1778 0.2794)
						)
						(arc
							(start 0.1778 0.2794)
							(mid 0.249642 0.249642)
							(end 0.2794 0.1778)
						)
						(arc
							(start 0.2794 -0.1778)
							(mid 0.249642 -0.249642)
							(end 0.1778 -0.2794)
						)
					)
					(width 0)
					(fill yes)
				)
			)
		)
		(pad "2" smd custom
			(at 0 0.4445 90)
			(size 0.1397 0.1397)
			(layers "F.Cu" "F.Mask" "F.Paste")
			(net "P3V3_STBY_RF")
			(options
				(clearance outline)
				(anchor circle)
			)
			(primitives
				(gr_poly
					(pts
						(arc
							(start -0.1778 -0.2794)
							(mid -0.249642 -0.249642)
							(end -0.2794 -0.1778)
						)
						(arc
							(start -0.2794 0.1778)
							(mid -0.249642 0.249642)
							(end -0.1778 0.2794)
						)
						(arc
							(start 0.1778 0.2794)
							(mid 0.249642 0.249642)
							(end 0.2794 0.1778)
						)
						(arc
							(start 0.2794 -0.1778)
							(mid 0.249642 -0.249642)
							(end 0.1778 -0.2794)
						)
					)
					(width 0)
					(fill yes)
				)
			)
		)
	)
	(footprint ""
		(layer "F.Cu")
		(at 173.473872 -196.083936 180)
		(property "Reference" "R431"
			(at 0 0 180)
			(layer "F.SilkS")
			(hide yes)
			(effects
				(font
					(size 1.27 1.27)
				)
			)
		)
		(property "Value" "0R2J-2-GP"
			(at 0.064008 -3.993896 180)
			(unlocked yes)
			(layer "F.Fab")
			(hide yes)
			(effects
				(font
					(size 1.016 1.016)
					(thickness 0.1524)
				)
			)
		)
		(property "Device Type" "R402H16"
			(at 0.064008 -5.517896 180)
			(unlocked yes)
			(layer "F.Fab")
			(hide yes)
			(effects
				(font
					(size 1.016 1.016)
					(thickness 0.1524)
				)
			)
		)
		(duplicate_pad_numbers_are_jumpers no)
		(fp_line
			(start 0.508 -0.9398)
			(end -0.508 -0.9398)
			(stroke
				(width 0.1524)
				(type default)
			)
			(layer "F.SilkS")
		)
		(fp_line
			(start -0.508 -0.9398)
			(end -0.508 0.9398)
			(stroke
				(width 0.1524)
				(type default)
			)
			(layer "F.SilkS")
		)
		(fp_rect
			(start -0.508 0.9398)
			(end 0.508 -0.9398)
			(stroke
				(width 0)
				(type default)
			)
			(fill no)
			(layer "F.CrtYd")
		)
		(fp_rect
			(start -0.508 0.9398)
			(end 0.508 -0.9398)
			(stroke
				(width 0)
				(type default)
			)
			(fill no)
			(layer "F.Fab")
		)
		(pad "1" smd custom
			(at 0 -0.4445 180)
			(size 0.1397 0.1397)
			(layers "F.Cu" "F.Mask" "F.Paste")
			(net "SAS_I2C_C_BUF_SCL")
			(options
				(clearance outline)
				(anchor circle)
			)
			(primitives
				(gr_poly
					(pts
						(arc
							(start -0.1778 -0.2794)
							(mid -0.249642 -0.249642)
							(end -0.2794 -0.1778)
						)
						(arc
							(start -0.2794 0.1778)
							(mid -0.249642 0.249642)
							(end -0.1778 0.2794)
						)
						(arc
							(start 0.1778 0.2794)
							(mid 0.249642 0.249642)
							(end 0.2794 0.1778)
						)
						(arc
							(start 0.2794 -0.1778)
							(mid 0.249642 -0.249642)
							(end 0.1778 -0.2794)
						)
					)
					(width 0)
					(fill yes)
				)
			)
		)
		(pad "2" smd custom
			(at 0 0.4445 180)
			(size 0.1397 0.1397)
			(layers "F.Cu" "F.Mask" "F.Paste")
			(net "BMC_I2C_C_SCL")
			(options
				(clearance outline)
				(anchor circle)
			)
			(primitives
				(gr_poly
					(pts
						(arc
							(start -0.1778 -0.2794)
							(mid -0.249642 -0.249642)
							(end -0.2794 -0.1778)
						)
						(arc
							(start -0.2794 0.1778)
							(mid -0.249642 0.249642)
							(end -0.1778 0.2794)
						)
						(arc
							(start 0.1778 0.2794)
							(mid 0.249642 0.249642)
							(end 0.2794 0.1778)
						)
						(arc
							(start 0.2794 -0.1778)
							(mid 0.249642 -0.249642)
							(end 0.1778 -0.2794)
						)
					)
					(width 0)
					(fill yes)
				)
			)
		)
	)
	(footprint ""
		(layer "F.Cu")
		(at 308.102 -180.975)
		(property "Reference" "TP100"
			(at 0 0 0)
			(layer "F.SilkS")
			(hide yes)
			(effects
				(font
					(size 1.27 1.27)
				)
			)
		)
		(property "Value" "TPAD28"
			(at 0.0127 -1.8034 0)
			(unlocked yes)
			(layer "F.Fab")
			(hide yes)
			(effects
				(font
					(size 1.016 1.016)
					(thickness 0.1524)
				)
			)
		)
		(property "Device Type" "TPAD28"
			(at 0.0127 -3.3274 0)
			(unlocked yes)
			(layer "F.Fab")
			(hide yes)
			(effects
				(font
					(size 1.016 1.016)
					(thickness 0.1524)
				)
			)
		)
		(duplicate_pad_numbers_are_jumpers no)
		(fp_poly
			(pts
				(arc
					(start 0.3556 0)
					(mid -0.3556 0)
					(end 0.3556 0)
				)
			)
			(stroke
				(width 0)
				(type default)
			)
			(fill no)
			(layer "F.CrtYd")
		)
		(fp_poly
			(pts
				(arc
					(start 0.6096 0)
					(mid -0.6096 0)
					(end 0.6096 0)
				)
			)
			(stroke
				(width 0)
				(type default)
			)
			(fill no)
			(layer "F.Fab")
		)
		(pad "1" smd circle
			(at 0 0)
			(size 0.7112 0.7112)
			(layers "F.Cu" "F.Mask" "F.Paste")
			(net "TP_BMC_GPIOL3")
		)
	)
	(footprint ""
		(layer "F.Cu")
		(at 165.598856 -112.404652)
		(property "Reference" "PC187"
			(at 0 0 0)
			(layer "F.SilkS")
			(hide yes)
			(effects
				(font
					(size 1.27 1.27)
				)
			)
		)
		(property "Value" "SC1U10V2KX-1GP"
			(at 1.1811 -2.7051 0)
			(unlocked yes)
			(layer "F.Fab")
			(hide yes)
			(effects
				(font
					(size 1.016 1.016)
					(thickness 0.1524)
				)
			)
		)
		(property "Device Type" "C402H22"
			(at 1.1811 -4.2291 0)
			(unlocked yes)
			(layer "F.Fab")
			(hide yes)
			(effects
				(font
					(size 1.016 1.016)
					(thickness 0.1524)
				)
			)
		)
		(duplicate_pad_numbers_are_jumpers no)
		(fp_rect
			(start -0.4318 0.9525)
			(end 0.4318 -0.9525)
			(stroke
				(width 0)
				(type default)
			)
			(fill no)
			(layer "F.CrtYd")
		)
		(fp_rect
			(start -0.4318 0.9525)
			(end 0.4318 -0.9525)
			(stroke
				(width 0)
				(type default)
			)
			(fill no)
			(layer "F.Fab")
		)
		(pad "1" smd custom
			(at 0 -0.4445)
			(size 0.1524 0.1524)
			(layers "F.Cu" "F.Mask" "F.Paste")
			(net "GND")
			(options
				(clearance outline)
				(anchor circle)
			)
			(primitives
				(gr_poly
					(pts
						(arc
							(start 0.3048 -0.2032)
							(mid 0.275042 -0.275042)
							(end 0.2032 -0.3048)
						)
						(arc
							(start -0.2032 -0.3048)
							(mid -0.275042 -0.275042)
							(end -0.3048 -0.2032)
						)
						(arc
							(start -0.3048 0.2032)
							(mid -0.275042 0.275042)
							(end -0.2032 0.3048)
						)
						(arc
							(start 0.2032 0.3048)
							(mid 0.275042 0.275042)
							(end 0.3048 0.2032)
						)
					)
					(width 0)
					(fill yes)
				)
			)
		)
		(pad "2" smd custom
			(at 0 0.4445)
			(size 0.1524 0.1524)
			(layers "F.Cu" "F.Mask" "F.Paste")
			(net "P0V9_E_EN")
			(options
				(clearance outline)
				(anchor circle)
			)
			(primitives
				(gr_poly
					(pts
						(arc
							(start 0.3048 -0.2032)
							(mid 0.275042 -0.275042)
							(end 0.2032 -0.3048)
						)
						(arc
							(start -0.2032 -0.3048)
							(mid -0.275042 -0.275042)
							(end -0.3048 -0.2032)
						)
						(arc
							(start -0.3048 0.2032)
							(mid -0.275042 0.275042)
							(end -0.2032 0.3048)
						)
						(arc
							(start 0.2032 0.3048)
							(mid 0.275042 0.275042)
							(end 0.3048 0.2032)
						)
					)
					(width 0)
					(fill yes)
				)
			)
		)
	)
	(footprint ""
		(layer "F.Cu")
		(at 308.791864 -205.096872)
		(property "Reference" "R168"
			(at 0 0 0)
			(layer "F.SilkS")
			(hide yes)
			(effects
				(font
					(size 1.27 1.27)
				)
			)
		)
		(property "Value" "0R2J-2-GP"
			(at 0.064008 -3.993896 0)
			(unlocked yes)
			(layer "F.Fab")
			(hide yes)
			(effects
				(font
					(size 1.016 1.016)
					(thickness 0.1524)
				)
			)
		)
		(property "Device Type" "R402H16"
			(at 0.064008 -5.517896 0)
			(unlocked yes)
			(layer "F.Fab")
			(hide yes)
			(effects
				(font
					(size 1.016 1.016)
					(thickness 0.1524)
				)
			)
		)
		(duplicate_pad_numbers_are_jumpers no)
		(fp_line
			(start -0.508 -0.9398)
			(end -0.508 0.9398)
			(stroke
				(width 0.1524)
				(type default)
			)
			(layer "F.SilkS")
		)
		(fp_line
			(start 0.508 -0.9398)
			(end -0.508 -0.9398)
			(stroke
				(width 0.1524)
				(type default)
			)
			(layer "F.SilkS")
		)
		(fp_rect
			(start -0.508 0.9398)
			(end 0.508 -0.9398)
			(stroke
				(width 0)
				(type default)
			)
			(fill no)
			(layer "F.CrtYd")
		)
		(fp_rect
			(start -0.508 0.9398)
			(end 0.508 -0.9398)
			(stroke
				(width 0)
				(type default)
			)
			(fill no)
			(layer "F.Fab")
		)
		(pad "1" smd custom
			(at 0 -0.4445)
			(size 0.1397 0.1397)
			(layers "F.Cu" "F.Mask" "F.Paste")
			(net "BMC_I2C_A_SCL")
			(options
				(clearance outline)
				(anchor circle)
			)
			(primitives
				(gr_poly
					(pts
						(arc
							(start -0.1778 -0.2794)
							(mid -0.249642 -0.249642)
							(end -0.2794 -0.1778)
						)
						(arc
							(start -0.2794 0.1778)
							(mid -0.249642 0.249642)
							(end -0.1778 0.2794)
						)
						(arc
							(start 0.1778 0.2794)
							(mid 0.249642 0.249642)
							(end 0.2794 0.1778)
						)
						(arc
							(start 0.2794 -0.1778)
							(mid 0.249642 -0.249642)
							(end 0.1778 -0.2794)
						)
					)
					(width 0)
					(fill yes)
				)
			)
		)
		(pad "2" smd custom
			(at 0 0.4445)
			(size 0.1397 0.1397)
			(layers "F.Cu" "F.Mask" "F.Paste")
			(net "LED_DR_I2C_SCL")
			(options
				(clearance outline)
				(anchor circle)
			)
			(primitives
				(gr_poly
					(pts
						(arc
							(start -0.1778 -0.2794)
							(mid -0.249642 -0.249642)
							(end -0.2794 -0.1778)
						)
						(arc
							(start -0.2794 0.1778)
							(mid -0.249642 0.249642)
							(end -0.1778 0.2794)
						)
						(arc
							(start 0.1778 0.2794)
							(mid 0.249642 0.249642)
							(end 0.2794 0.1778)
						)
						(arc
							(start 0.2794 -0.1778)
							(mid 0.249642 -0.249642)
							(end 0.1778 -0.2794)
						)
					)
					(width 0)
					(fill yes)
				)
			)
		)
	)
	(footprint ""
		(layer "F.Cu")
		(at 279.772872 -215.591136 180)
		(property "Reference" "R456"
			(at 0 0 180)
			(layer "F.SilkS")
			(hide yes)
			(effects
				(font
					(size 1.27 1.27)
				)
			)
		)
		(property "Value" "4K75R2F-1-GP"
			(at 0.064008 -3.993896 180)
			(unlocked yes)
			(layer "F.Fab")
			(hide yes)
			(effects
				(font
					(size 1.016 1.016)
					(thickness 0.1524)
				)
			)
		)
		(property "Device Type" "R402H16"
			(at 0.064008 -5.517896 180)
			(unlocked yes)
			(layer "F.Fab")
			(hide yes)
			(effects
				(font
					(size 1.016 1.016)
					(thickness 0.1524)
				)
			)
		)
		(duplicate_pad_numbers_are_jumpers no)
		(fp_line
			(start 0.508 -0.9398)
			(end -0.508 -0.9398)
			(stroke
				(width 0.1524)
				(type default)
			)
			(layer "F.SilkS")
		)
		(fp_line
			(start -0.508 -0.9398)
			(end -0.508 0.9398)
			(stroke
				(width 0.1524)
				(type default)
			)
			(layer "F.SilkS")
		)
		(fp_rect
			(start -0.508 0.9398)
			(end 0.508 -0.9398)
			(stroke
				(width 0)
				(type default)
			)
			(fill no)
			(layer "F.CrtYd")
		)
		(fp_rect
			(start -0.508 0.9398)
			(end 0.508 -0.9398)
			(stroke
				(width 0)
				(type default)
			)
			(fill no)
			(layer "F.Fab")
		)
		(pad "1" smd custom
			(at 0 -0.4445 180)
			(size 0.1397 0.1397)
			(layers "F.Cu" "F.Mask" "F.Paste")
			(net "P3V3_STBY")
			(options
				(clearance outline)
				(anchor circle)
			)
			(primitives
				(gr_poly
					(pts
						(arc
							(start -0.1778 -0.2794)
							(mid -0.249642 -0.249642)
							(end -0.2794 -0.1778)
						)
						(arc
							(start -0.2794 0.1778)
							(mid -0.249642 0.249642)
							(end -0.1778 0.2794)
						)
						(arc
							(start 0.1778 0.2794)
							(mid 0.249642 0.249642)
							(end 0.2794 0.1778)
						)
						(arc
							(start 0.2794 -0.1778)
							(mid 0.249642 -0.249642)
							(end 0.1778 -0.2794)
						)
					)
					(width 0)
					(fill yes)
				)
			)
		)
		(pad "2" smd custom
			(at 0 0.4445 180)
			(size 0.1397 0.1397)
			(layers "F.Cu" "F.Mask" "F.Paste")
			(net "TPS74801_1V53_STBY_EN")
			(options
				(clearance outline)
				(anchor circle)
			)
			(primitives
				(gr_poly
					(pts
						(arc
							(start -0.1778 -0.2794)
							(mid -0.249642 -0.249642)
							(end -0.2794 -0.1778)
						)
						(arc
							(start -0.2794 0.1778)
							(mid -0.249642 0.249642)
							(end -0.1778 0.2794)
						)
						(arc
							(start 0.1778 0.2794)
							(mid 0.249642 0.249642)
							(end 0.2794 0.1778)
						)
						(arc
							(start 0.2794 -0.1778)
							(mid 0.249642 -0.249642)
							(end 0.1778 -0.2794)
						)
					)
					(width 0)
					(fill yes)
				)
			)
		)
	)
)
